# BASEBOARD_FAB2 (Tioga Pass) — schematic netlist excerpt (pin names and nets, part order shuffled) for the footprints in the layout excerpt that follows; sources: Cadence DE-HDL packaged netlist, KiCad conversion of Wiwynn_Tioga_Pass_MB.brd

R2W4  RES  0.0 5% CHIP  pkg 0402  page 119 : A = FM_PMBUS_ALERT_BUF_EN_N ; B = FM_PMBUS_ALERT_BUF_EN_R2_N

(kicad_pcb
	(version 20260206)
	(generator "pcbnew")
	(generator_version "10.0")
	(general
		(thickness 1.6)
		(legacy_teardrops no)
	)
	(paper "A4")
	(title_block
		(title "Wiwynn_Tioga_Pass_MB.brd")
		(comment 1 "Tioga Pass / footprints 3054-3054 of 4770")
	)
	(layers
		(0 "F.Cu" signal "TOP")
		(4 "In1.Cu" signal "L2GND")
		(6 "In2.Cu" signal "L3")
		(8 "In3.Cu" signal "L4GND")
		(10 "In4.Cu" signal "L5")
		(12 "In5.Cu" signal "L6GND")
		(14 "In6.Cu" signal "L7VCC")
		(16 "In7.Cu" signal "L8VCC")
		(18 "In8.Cu" signal "L9GND")
		(20 "In9.Cu" signal "L10")
		(22 "In10.Cu" signal "L11GND")
		(24 "In11.Cu" signal "L12")
		(26 "In12.Cu" signal "L13GND")
		(2 "B.Cu" signal "BOTTOM")
		(9 "F.Adhes" user "F.Adhesive")
		(11 "B.Adhes" user "B.Adhesive")
		(13 "F.Paste" user "Package Geometry/Pastemask Top")
		(15 "B.Paste" user "Package Geometry/Pastemask Bottom")
		(5 "F.SilkS" user "Ref Des/Silkscreen Top")
		(7 "B.SilkS" user "Ref Des/Silkscreen Bottom")
		(1 "F.Mask" user "Board Geometry/Soldermask Top")
		(3 "B.Mask" user "Board Geometry/Soldermask Bottom")
		(17 "Dwgs.User" user "User.Drawings")
		(19 "Cmts.User" user "User.Comments")
		(21 "Eco1.User" user "User.Eco1")
		(23 "Eco2.User" user "User.Eco2")
		(25 "Edge.Cuts" user "Board Geometry/Outline")
		(27 "Margin" user)
		(31 "F.CrtYd" user "Package Geometry/Place Bound Top")
		(29 "B.CrtYd" user "Package Geometry/Place Bound Bottom")
		(35 "F.Fab" user "Ref Des/Assembly Top")
		(33 "B.Fab" user "Ref Des/Assembly Bottom")
	)
	(footprint ""
		(layer "B.Cu")
		(at 393.581128 -89.622884 -90)
		(property "Reference" "R2W4"
			(at 0.8382 -0.67818 270)
			(unlocked yes)
			(layer "B.SilkS")
			(effects
				(font
					(size 0.4064 0.254)
					(thickness 0.1524)
				)
				(justify left mirror)
			)
		)
		(property "Value" ""
			(at 0 0 90)
			(layer "B.Fab")
			(effects
				(font
					(size 1.27 1.27)
				)
				(justify mirror)
			)
		)
		(duplicate_pad_numbers_are_jumpers no)
		(fp_poly
			(pts
				(xy 0.2794 -0.1016) (xy -0.2794 -0.1016) (xy -0.2794 0.9906) (xy 0.2794 0.9906)
			)
			(stroke
				(width 0)
				(type default)
			)
			(fill no)
			(layer "B.CrtYd")
		)
		(fp_line
			(start -0.2794 0.9906)
			(end -0.2794 -0.1016)
			(stroke
				(width 0.1)
				(type default)
			)
			(layer "B.Fab")
		)
		(fp_line
			(start 0.2794 0.9906)
			(end -0.2794 0.9906)
			(stroke
				(width 0.1)
				(type default)
			)
			(layer "B.Fab")
		)
		(fp_line
			(start -0.2794 -0.1016)
			(end 0.2794 -0.1016)
			(stroke
				(width 0.1)
				(type default)
			)
			(layer "B.Fab")
		)
		(fp_line
			(start 0.2794 -0.1016)
			(end 0.2794 0.9906)
			(stroke
				(width 0.1)
				(type default)
			)
			(layer "B.Fab")
		)
		(pad "1" smd rect
			(at 0 0 90)
			(size 0.508 0.508)
			(layers "B.Cu" "B.Mask" "B.Paste")
			(net "FM_PMBUS_ALERT_BUF_EN_N")
		)
		(pad "2" smd rect
			(at 0 0.889 90)
			(size 0.508 0.508)
			(layers "B.Cu" "B.Mask" "B.Paste")
			(net "FM_PMBUS_ALERT_BUF_EN_R2_N")
		)
		(zone
			(layer "B.Cu")
			(hatch none 0.5)
			(connect_pads
				(clearance 0)
			)
			(min_thickness 0.25)
			(keepout
				(tracks not_allowed)
				(vias allowed)
				(pads allowed)
				(copperpour not_allowed)
				(footprints allowed)
			)
			(placement
				(enabled no)
				(sheetname "")
			)
			(fill
				(thermal_gap 0.5)
				(thermal_bridge_width 0.5)
				(island_removal_mode 0)
			)
			(polygon
				(pts
					(xy 392.946128 -89.368884) (xy 392.946128 -89.876884) (xy 393.327128 -89.876884) (xy 393.327128 -89.368884)
				)
			)
		)
		(zone
			(layer "B.Cu")
			(hatch none 0.5)
			(connect_pads
				(clearance 0)
			)
			(min_thickness 0.25)
			(keepout
				(tracks allowed)
				(vias not_allowed)
				(pads allowed)
				(copperpour not_allowed)
				(footprints allowed)
			)
			(placement
				(enabled no)
				(sheetname "")
			)
			(fill
				(thermal_gap 0.5)
				(thermal_bridge_width 0.5)
				(island_removal_mode 0)
			)
			(polygon
				(pts
					(xy 393.327128 -89.368884) (xy 393.327128 -89.876884) (xy 392.946128 -89.876884) (xy 392.946128 -89.368884)
				)
			)
		)
	)
)
